(kicad_pcb
	(version 20260206)
	(generator "pcbnew")
	(generator_version "10.0")
	(general
		(thickness 1.6)
		(legacy_teardrops no)
	)
	(paper "A4")
	(title_block
		(title "04192023_DAF0TMB3IC0_F0TG_MB_C_brd_V02_OCP.brd")
		(comment 1 "Grand Teton / footprints 216-221 of 8354")
	)
	(layers
		(0 "F.Cu" signal "TOP")
		(4 "In1.Cu" signal "GND")
		(6 "In2.Cu" signal "IN1")
		(8 "In3.Cu" signal "GND1")
		(10 "In4.Cu" signal "IN2")
		(12 "In5.Cu" signal "GND2")
		(14 "In6.Cu" signal "IN3")
		(16 "In7.Cu" signal "GND3")
		(18 "In8.Cu" signal "VCC")
		(20 "In9.Cu" signal "VCC1")
		(22 "In10.Cu" signal "GND4")
		(24 "In11.Cu" signal "IN4")
		(26 "In12.Cu" signal "GND5")
		(28 "In13.Cu" signal "IN5")
		(30 "In14.Cu" signal "GND6")
		(32 "In15.Cu" signal "IN6")
		(34 "In16.Cu" signal "GND7")
		(2 "B.Cu" signal "BOTTOM")
		(9 "F.Adhes" user "F.Adhesive")
		(11 "B.Adhes" user "B.Adhesive")
		(13 "F.Paste" user "Package Geometry/Pastemask Top")
		(15 "B.Paste" user "Package Geometry/Pastemask Bottom")
		(5 "F.SilkS" user "Ref Des/Silkscreen Top")
		(7 "B.SilkS" user "Ref Des/Silkscreen Bottom")
		(1 "F.Mask" user "Board Geometry/Soldermask Top")
		(3 "B.Mask" user "Board Geometry/Soldermask Bottom")
		(17 "Dwgs.User" user "User.Drawings")
		(19 "Cmts.User" user "User.Comments")
		(21 "Eco1.User" user "User.Eco1")
		(23 "Eco2.User" user "User.Eco2")
		(25 "Edge.Cuts" user "Board Geometry/Outline")
		(27 "Margin" user)
		(31 "F.CrtYd" user "Package Geometry/Place Bound Top")
		(29 "B.CrtYd" user "Package Geometry/Place Bound Bottom")
		(35 "F.Fab" user "Ref Des/Assembly Top")
		(33 "B.Fab" user "Ref Des/Assembly Bottom")
	)
	(footprint ""
		(layer "F.Cu")
		(at 49.657 -37.846)
		(property "Reference" "R1149"
			(at 0 0 0)
			(layer "F.SilkS")
			(hide yes)
			(effects
				(font
					(size 1.27 1.27)
				)
			)
		)
		(property "Value" ""
			(at 0 0 0)
			(layer "F.Fab")
			(effects
				(font
					(size 1.27 1.27)
				)
			)
		)
		(duplicate_pad_numbers_are_jumpers no)
		(fp_line
			(start -0.7874 -0.4064)
			(end 0.7874 -0.4064)
			(stroke
				(width 0.1524)
				(type default)
			)
			(layer "F.SilkS")
		)
		(fp_line
			(start -0.7874 0.4064)
			(end -0.7874 -0.4064)
			(stroke
				(width 0.1524)
				(type default)
			)
			(layer "F.SilkS")
		)
		(fp_line
			(start 0.7874 -0.4064)
			(end 0.7874 0.4064)
			(stroke
				(width 0.1524)
				(type default)
			)
			(layer "F.SilkS")
		)
		(fp_line
			(start 0.7874 0.4064)
			(end -0.7874 0.4064)
			(stroke
				(width 0.1524)
				(type default)
			)
			(layer "F.SilkS")
		)
		(fp_line
			(start -0.67945 -0.305054)
			(end -0.12065 -0.305054)
			(stroke
				(width 0.1)
				(type default)
			)
			(layer "F.Fab")
		)
		(fp_line
			(start -0.67945 0.3048)
			(end -0.67945 -0.305054)
			(stroke
				(width 0.1)
				(type default)
			)
			(layer "F.Fab")
		)
		(fp_line
			(start -0.12065 -0.305054)
			(end -0.12065 -0.2794)
			(stroke
				(width 0.1)
				(type default)
			)
			(layer "F.Fab")
		)
		(fp_line
			(start -0.12065 -0.2794)
			(end 0.12065 -0.2794)
			(stroke
				(width 0.1)
				(type default)
			)
			(layer "F.Fab")
		)
		(fp_line
			(start -0.12065 0.2794)
			(end -0.12065 0.3048)
			(stroke
				(width 0.1)
				(type default)
			)
			(layer "F.Fab")
		)
		(fp_line
			(start -0.12065 0.3048)
			(end -0.67945 0.3048)
			(stroke
				(width 0.1)
				(type default)
			)
			(layer "F.Fab")
		)
		(fp_line
			(start 0.120396 0.2794)
			(end -0.12065 0.2794)
			(stroke
				(width 0.1)
				(type default)
			)
			(layer "F.Fab")
		)
		(fp_line
			(start 0.120396 0.3048)
			(end 0.120396 0.2794)
			(stroke
				(width 0.1)
				(type default)
			)
			(layer "F.Fab")
		)
		(fp_line
			(start 0.12065 -0.3048)
			(end 0.67945 -0.3048)
			(stroke
				(width 0.1)
				(type default)
			)
			(layer "F.Fab")
		)
		(fp_line
			(start 0.12065 -0.2794)
			(end 0.12065 -0.3048)
			(stroke
				(width 0.1)
				(type default)
			)
			(layer "F.Fab")
		)
		(fp_line
			(start 0.67945 -0.3048)
			(end 0.67945 0.3048)
			(stroke
				(width 0.1)
				(type default)
			)
			(layer "F.Fab")
		)
		(fp_line
			(start 0.67945 0.3048)
			(end 0.120396 0.3048)
			(stroke
				(width 0.1)
				(type default)
			)
			(layer "F.Fab")
		)
		(pad "1" smd circle
			(at -0.40005 0)
			(size 0 0)
			(layers "F.Cu" "F.Mask" "F.Paste")
			(net "P3V3_AUX")
		)
		(pad "2" smd circle
			(at 0.40005 0)
			(size 0 0)
			(layers "F.Cu" "F.Mask" "F.Paste")
			(net "HP_LVC3_OCP_V3_2_PRSNT2")
		)
	)
	(footprint ""
		(layer "F.Cu")
		(at 283.310076 -412.579058 -90)
		(property "Reference" "C2328"
			(at 0 0 270)
			(layer "F.SilkS")
			(hide yes)
			(effects
				(font
					(size 1.27 1.27)
				)
			)
		)
		(property "Value" ""
			(at 0 0 270)
			(layer "F.Fab")
			(effects
				(font
					(size 1.27 1.27)
				)
			)
		)
		(duplicate_pad_numbers_are_jumpers no)
		(fp_line
			(start -0.7874 0.4064)
			(end -0.7874 -0.4064)
			(stroke
				(width 0.1524)
				(type default)
			)
			(layer "F.SilkS")
		)
		(fp_line
			(start 0.7874 0.4064)
			(end -0.7874 0.4064)
			(stroke
				(width 0.1524)
				(type default)
			)
			(layer "F.SilkS")
		)
		(fp_line
			(start -0.7874 -0.4064)
			(end 0.7874 -0.4064)
			(stroke
				(width 0.1524)
				(type default)
			)
			(layer "F.SilkS")
		)
		(fp_line
			(start 0.7874 -0.4064)
			(end 0.7874 0.4064)
			(stroke
				(width 0.1524)
				(type default)
			)
			(layer "F.SilkS")
		)
		(fp_line
			(start -0.67945 0.3048)
			(end -0.67945 -0.305054)
			(stroke
				(width 0.1)
				(type default)
			)
			(layer "F.Fab")
		)
		(fp_line
			(start -0.12065 0.3048)
			(end -0.67945 0.3048)
			(stroke
				(width 0.1)
				(type default)
			)
			(layer "F.Fab")
		)
		(fp_line
			(start 0.120396 0.3048)
			(end 0.120396 0.2794)
			(stroke
				(width 0.1)
				(type default)
			)
			(layer "F.Fab")
		)
		(fp_line
			(start 0.67945 0.3048)
			(end 0.120396 0.3048)
			(stroke
				(width 0.1)
				(type default)
			)
			(layer "F.Fab")
		)
		(fp_line
			(start -0.12065 0.2794)
			(end -0.12065 0.3048)
			(stroke
				(width 0.1)
				(type default)
			)
			(layer "F.Fab")
		)
		(fp_line
			(start 0.120396 0.2794)
			(end -0.12065 0.2794)
			(stroke
				(width 0.1)
				(type default)
			)
			(layer "F.Fab")
		)
		(fp_line
			(start -0.12065 -0.2794)
			(end 0.12065 -0.2794)
			(stroke
				(width 0.1)
				(type default)
			)
			(layer "F.Fab")
		)
		(fp_line
			(start 0.12065 -0.2794)
			(end 0.12065 -0.3048)
			(stroke
				(width 0.1)
				(type default)
			)
			(layer "F.Fab")
		)
		(fp_line
			(start 0.12065 -0.3048)
			(end 0.67945 -0.3048)
			(stroke
				(width 0.1)
				(type default)
			)
			(layer "F.Fab")
		)
		(fp_line
			(start 0.67945 -0.3048)
			(end 0.67945 0.3048)
			(stroke
				(width 0.1)
				(type default)
			)
			(layer "F.Fab")
		)
		(fp_line
			(start -0.67945 -0.305054)
			(end -0.12065 -0.305054)
			(stroke
				(width 0.1)
				(type default)
			)
			(layer "F.Fab")
		)
		(fp_line
			(start -0.12065 -0.305054)
			(end -0.12065 -0.2794)
			(stroke
				(width 0.1)
				(type default)
			)
			(layer "F.Fab")
		)
		(pad "1" smd circle
			(at -0.40005 0 270)
			(size 0 0)
			(layers "F.Cu" "F.Mask" "F.Paste")
			(net "P3V3_9ZXL045_P0_VDD")
		)
		(pad "2" smd circle
			(at 0.40005 0 270)
			(size 0 0)
			(layers "F.Cu" "F.Mask" "F.Paste")
			(net "GND")
		)
	)
	(footprint ""
		(layer "F.Cu")
		(at 69.917818 -25.192482)
		(property "Reference" "PC2174"
			(at 0 0 0)
			(layer "F.SilkS")
			(hide yes)
			(effects
				(font
					(size 1.27 1.27)
				)
			)
		)
		(property "Value" ""
			(at 0 0 0)
			(layer "F.Fab")
			(effects
				(font
					(size 1.27 1.27)
				)
			)
		)
		(duplicate_pad_numbers_are_jumpers no)
		(fp_line
			(start -0.7874 -0.4064)
			(end 0.7874 -0.4064)
			(stroke
				(width 0.1524)
				(type default)
			)
			(layer "F.SilkS")
		)
		(fp_line
			(start -0.7874 0.4064)
			(end -0.7874 -0.4064)
			(stroke
				(width 0.1524)
				(type default)
			)
			(layer "F.SilkS")
		)
		(fp_line
			(start 0.7874 -0.4064)
			(end 0.7874 0.4064)
			(stroke
				(width 0.1524)
				(type default)
			)
			(layer "F.SilkS")
		)
		(fp_line
			(start 0.7874 0.4064)
			(end -0.7874 0.4064)
			(stroke
				(width 0.1524)
				(type default)
			)
			(layer "F.SilkS")
		)
		(fp_line
			(start -0.67945 -0.305054)
			(end -0.12065 -0.305054)
			(stroke
				(width 0.1)
				(type default)
			)
			(layer "F.Fab")
		)
		(fp_line
			(start -0.67945 0.3048)
			(end -0.67945 -0.305054)
			(stroke
				(width 0.1)
				(type default)
			)
			(layer "F.Fab")
		)
		(fp_line
			(start -0.12065 -0.305054)
			(end -0.12065 -0.2794)
			(stroke
				(width 0.1)
				(type default)
			)
			(layer "F.Fab")
		)
		(fp_line
			(start -0.12065 -0.2794)
			(end 0.12065 -0.2794)
			(stroke
				(width 0.1)
				(type default)
			)
			(layer "F.Fab")
		)
		(fp_line
			(start -0.12065 0.2794)
			(end -0.12065 0.3048)
			(stroke
				(width 0.1)
				(type default)
			)
			(layer "F.Fab")
		)
		(fp_line
			(start -0.12065 0.3048)
			(end -0.67945 0.3048)
			(stroke
				(width 0.1)
				(type default)
			)
			(layer "F.Fab")
		)
		(fp_line
			(start 0.120396 0.2794)
			(end -0.12065 0.2794)
			(stroke
				(width 0.1)
				(type default)
			)
			(layer "F.Fab")
		)
		(fp_line
			(start 0.120396 0.3048)
			(end 0.120396 0.2794)
			(stroke
				(width 0.1)
				(type default)
			)
			(layer "F.Fab")
		)
		(fp_line
			(start 0.12065 -0.3048)
			(end 0.67945 -0.3048)
			(stroke
				(width 0.1)
				(type default)
			)
			(layer "F.Fab")
		)
		(fp_line
			(start 0.12065 -0.2794)
			(end 0.12065 -0.3048)
			(stroke
				(width 0.1)
				(type default)
			)
			(layer "F.Fab")
		)
		(fp_line
			(start 0.67945 -0.3048)
			(end 0.67945 0.3048)
			(stroke
				(width 0.1)
				(type default)
			)
			(layer "F.Fab")
		)
		(fp_line
			(start 0.67945 0.3048)
			(end 0.120396 0.3048)
			(stroke
				(width 0.1)
				(type default)
			)
			(layer "F.Fab")
		)
		(pad "1" smd circle
			(at -0.40005 0)
			(size 0 0)
			(layers "F.Cu" "F.Mask" "F.Paste")
			(net "P12V_OCP_V3_2")
		)
		(pad "2" smd circle
			(at 0.40005 0)
			(size 0 0)
			(layers "F.Cu" "F.Mask" "F.Paste")
			(net "GND")
		)
	)
	(footprint ""
		(layer "F.Cu")
		(at 139.749784 -47.309024 -90)
		(property "Reference" "R6207"
			(at 0 0 270)
			(layer "F.SilkS")
			(hide yes)
			(effects
				(font
					(size 1.27 1.27)
				)
			)
		)
		(property "Value" ""
			(at 0 0 270)
			(layer "F.Fab")
			(effects
				(font
					(size 1.27 1.27)
				)
			)
		)
		(duplicate_pad_numbers_are_jumpers no)
		(fp_line
			(start -0.7874 0.4064)
			(end -0.7874 -0.4064)
			(stroke
				(width 0.1524)
				(type default)
			)
			(layer "F.SilkS")
		)
		(fp_line
			(start 0.7874 0.4064)
			(end -0.7874 0.4064)
			(stroke
				(width 0.1524)
				(type default)
			)
			(layer "F.SilkS")
		)
		(fp_line
			(start -0.7874 -0.4064)
			(end 0.7874 -0.4064)
			(stroke
				(width 0.1524)
				(type default)
			)
			(layer "F.SilkS")
		)
		(fp_line
			(start 0.7874 -0.4064)
			(end 0.7874 0.4064)
			(stroke
				(width 0.1524)
				(type default)
			)
			(layer "F.SilkS")
		)
		(fp_line
			(start -0.67945 0.3048)
			(end -0.67945 -0.305054)
			(stroke
				(width 0.1)
				(type default)
			)
			(layer "F.Fab")
		)
		(fp_line
			(start -0.12065 0.3048)
			(end -0.67945 0.3048)
			(stroke
				(width 0.1)
				(type default)
			)
			(layer "F.Fab")
		)
		(fp_line
			(start 0.120396 0.3048)
			(end 0.120396 0.2794)
			(stroke
				(width 0.1)
				(type default)
			)
			(layer "F.Fab")
		)
		(fp_line
			(start 0.67945 0.3048)
			(end 0.120396 0.3048)
			(stroke
				(width 0.1)
				(type default)
			)
			(layer "F.Fab")
		)
		(fp_line
			(start -0.12065 0.2794)
			(end -0.12065 0.3048)
			(stroke
				(width 0.1)
				(type default)
			)
			(layer "F.Fab")
		)
		(fp_line
			(start 0.120396 0.2794)
			(end -0.12065 0.2794)
			(stroke
				(width 0.1)
				(type default)
			)
			(layer "F.Fab")
		)
		(fp_line
			(start -0.12065 -0.2794)
			(end 0.12065 -0.2794)
			(stroke
				(width 0.1)
				(type default)
			)
			(layer "F.Fab")
		)
		(fp_line
			(start 0.12065 -0.2794)
			(end 0.12065 -0.3048)
			(stroke
				(width 0.1)
				(type default)
			)
			(layer "F.Fab")
		)
		(fp_line
			(start 0.12065 -0.3048)
			(end 0.67945 -0.3048)
			(stroke
				(width 0.1)
				(type default)
			)
			(layer "F.Fab")
		)
		(fp_line
			(start 0.67945 -0.3048)
			(end 0.67945 0.3048)
			(stroke
				(width 0.1)
				(type default)
			)
			(layer "F.Fab")
		)
		(fp_line
			(start -0.67945 -0.305054)
			(end -0.12065 -0.305054)
			(stroke
				(width 0.1)
				(type default)
			)
			(layer "F.Fab")
		)
		(fp_line
			(start -0.12065 -0.305054)
			(end -0.12065 -0.2794)
			(stroke
				(width 0.1)
				(type default)
			)
			(layer "F.Fab")
		)
		(pad "1" smd circle
			(at -0.40005 0 270)
			(size 0 0)
			(layers "F.Cu" "F.Mask" "F.Paste")
			(net "P3V3_AUX")
		)
		(pad "2" smd circle
			(at 0.40005 0 270)
			(size 0 0)
			(layers "F.Cu" "F.Mask" "F.Paste")
			(net "PU_CPU0_USB_HUB_RESERVED1")
		)
	)
	(footprint ""
		(layer "F.Cu")
		(at 55.87873 -16.099536 90)
		(property "Reference" "C707"
			(at 0 0 90)
			(layer "F.SilkS")
			(hide yes)
			(effects
				(font
					(size 1.27 1.27)
				)
			)
		)
		(property "Value" ""
			(at 0 0 90)
			(layer "F.Fab")
			(effects
				(font
					(size 1.27 1.27)
				)
			)
		)
		(duplicate_pad_numbers_are_jumpers no)
		(fp_line
			(start 0.299974 -0.150114)
			(end 0.299974 0.150114)
			(stroke
				(width 0.1)
				(type default)
			)
			(layer "F.Fab")
		)
		(fp_line
			(start -0.299974 -0.150114)
			(end 0.299974 -0.150114)
			(stroke
				(width 0.1)
				(type default)
			)
			(layer "F.Fab")
		)
		(fp_line
			(start 0.299974 0.150114)
			(end -0.299974 0.150114)
			(stroke
				(width 0.1)
				(type default)
			)
			(layer "F.Fab")
		)
		(fp_line
			(start -0.299974 0.150114)
			(end -0.299974 -0.150114)
			(stroke
				(width 0.1)
				(type default)
			)
			(layer "F.Fab")
		)
		(pad "1" smd rect
			(at -0.2667 0 90)
			(size 0.3048 0.381)
			(layers "F.Cu" "F.Mask" "F.Paste")
			(net "P5E_CPU1_G1_TX_C_DP<1>")
		)
		(pad "2" smd rect
			(at 0.2667 0 90)
			(size 0.3048 0.381)
			(layers "F.Cu" "F.Mask" "F.Paste")
			(net "P5E_CPU1_G1_TX_DP<1>")
		)
	)
	(footprint ""
		(layer "F.Cu")
		(at 136.50468 -28.48102 90)
		(property "Reference" "R6196"
			(at 0 0 90)
			(layer "F.SilkS")
			(hide yes)
			(effects
				(font
					(size 1.27 1.27)
				)
			)
		)
		(property "Value" ""
			(at 0 0 90)
			(layer "F.Fab")
			(effects
				(font
					(size 1.27 1.27)
				)
			)
		)
		(duplicate_pad_numbers_are_jumpers no)
		(fp_line
			(start 0.32512 -0.175006)
			(end 0.32512 0.175006)
			(stroke
				(width 0.1)
				(type default)
			)
			(layer "F.Fab")
		)
		(fp_line
			(start -0.32512 -0.175006)
			(end 0.32512 -0.175006)
			(stroke
				(width 0.1)
				(type default)
			)
			(layer "F.Fab")
		)
		(fp_line
			(start 0.32512 0.175006)
			(end -0.32512 0.175006)
			(stroke
				(width 0.1)
				(type default)
			)
			(layer "F.Fab")
		)
		(fp_line
			(start -0.32512 0.175006)
			(end -0.32512 -0.175006)
			(stroke
				(width 0.1)
				(type default)
			)
			(layer "F.Fab")
		)
		(pad "1" smd rect
			(at -0.2667 0 90)
			(size 0.3048 0.381)
			(layers "F.Cu" "F.Mask" "F.Paste")
			(net "USB2_CPU0_P0_HUB2_R_DP")
		)
		(pad "2" smd rect
			(at 0.2667 0 270)
			(size 0.3048 0.381)
			(layers "F.Cu" "F.Mask" "F.Paste")
			(net "USB2_HUB_EXT_DP")
		)
	)
)
